(kicad_pcb
	(version 20260206)
	(generator "pcbnew")
	(generator_version "10.0")
	(general
		(thickness 1.6)
		(legacy_teardrops no)
	)
	(paper "A4")
	(title_block
		(title "04192023_DAF0TMB3IC0_F0TG_MB_C_brd_V02_OCP.brd")
		(comment 1 "Grand Teton / footprints 6720-6726 of 8354")
	)
	(layers
		(0 "F.Cu" signal "TOP")
		(4 "In1.Cu" signal "GND")
		(6 "In2.Cu" signal "IN1")
		(8 "In3.Cu" signal "GND1")
		(10 "In4.Cu" signal "IN2")
		(12 "In5.Cu" signal "GND2")
		(14 "In6.Cu" signal "IN3")
		(16 "In7.Cu" signal "GND3")
		(18 "In8.Cu" signal "VCC")
		(20 "In9.Cu" signal "VCC1")
		(22 "In10.Cu" signal "GND4")
		(24 "In11.Cu" signal "IN4")
		(26 "In12.Cu" signal "GND5")
		(28 "In13.Cu" signal "IN5")
		(30 "In14.Cu" signal "GND6")
		(32 "In15.Cu" signal "IN6")
		(34 "In16.Cu" signal "GND7")
		(2 "B.Cu" signal "BOTTOM")
		(9 "F.Adhes" user "F.Adhesive")
		(11 "B.Adhes" user "B.Adhesive")
		(13 "F.Paste" user "Package Geometry/Pastemask Top")
		(15 "B.Paste" user "Package Geometry/Pastemask Bottom")
		(5 "F.SilkS" user "Ref Des/Silkscreen Top")
		(7 "B.SilkS" user "Ref Des/Silkscreen Bottom")
		(1 "F.Mask" user "Board Geometry/Soldermask Top")
		(3 "B.Mask" user "Board Geometry/Soldermask Bottom")
		(17 "Dwgs.User" user "User.Drawings")
		(19 "Cmts.User" user "User.Comments")
		(21 "Eco1.User" user "User.Eco1")
		(23 "Eco2.User" user "User.Eco2")
		(25 "Edge.Cuts" user "Board Geometry/Outline")
		(27 "Margin" user)
		(31 "F.CrtYd" user "Package Geometry/Place Bound Top")
		(29 "B.CrtYd" user "Package Geometry/Place Bound Bottom")
		(35 "F.Fab" user "Ref Des/Assembly Top")
		(33 "B.Fab" user "Ref Des/Assembly Bottom")
	)
	(footprint ""
		(layer "B.Cu")
		(at 254.635 -337.37804 180)
		(property "Reference" "R1375"
			(at 0 0 0)
			(layer "B.SilkS")
			(hide yes)
			(effects
				(font
					(size 1.27 1.27)
				)
				(justify mirror)
			)
		)
		(property "Value" ""
			(at 0 0 0)
			(layer "B.Fab")
			(effects
				(font
					(size 1.27 1.27)
				)
				(justify mirror)
			)
		)
		(duplicate_pad_numbers_are_jumpers no)
		(fp_line
			(start 0.32512 0.175006)
			(end 0.32512 -0.175006)
			(stroke
				(width 0.1)
				(type default)
			)
			(layer "B.Fab")
		)
		(fp_line
			(start 0.32512 -0.175006)
			(end -0.32512 -0.175006)
			(stroke
				(width 0.1)
				(type default)
			)
			(layer "B.Fab")
		)
		(fp_line
			(start -0.32512 0.175006)
			(end 0.32512 0.175006)
			(stroke
				(width 0.1)
				(type default)
			)
			(layer "B.Fab")
		)
		(fp_line
			(start -0.32512 -0.175006)
			(end -0.32512 0.175006)
			(stroke
				(width 0.1)
				(type default)
			)
			(layer "B.Fab")
		)
		(pad "1" smd rect
			(at 0.2667 0)
			(size 0.3048 0.381)
			(layers "B.Cu" "B.Mask" "B.Paste")
			(net "P1V8_CPU0_RT_1D")
		)
		(pad "2" smd rect
			(at -0.2667 0 180)
			(size 0.3048 0.381)
			(layers "B.Cu" "B.Mask" "B.Paste")
			(net "SMB_RT_CPU0_P3_ROM_MUX_2D_R_SDA")
		)
	)
	(footprint ""
		(layer "B.Cu")
		(at 113.841022 -27.04846)
		(property "Reference" "C6113"
			(at 0 0 0)
			(layer "B.SilkS")
			(hide yes)
			(effects
				(font
					(size 1.27 1.27)
				)
				(justify mirror)
			)
		)
		(property "Value" ""
			(at 0 0 0)
			(layer "B.Fab")
			(effects
				(font
					(size 1.27 1.27)
				)
				(justify mirror)
			)
		)
		(duplicate_pad_numbers_are_jumpers no)
		(fp_line
			(start -0.7874 -0.4064)
			(end -0.7874 0.4064)
			(stroke
				(width 0.1524)
				(type default)
			)
			(layer "B.SilkS")
		)
		(fp_line
			(start -0.7874 0.4064)
			(end 0.7874 0.4064)
			(stroke
				(width 0.1524)
				(type default)
			)
			(layer "B.SilkS")
		)
		(fp_line
			(start 0.7874 -0.4064)
			(end -0.7874 -0.4064)
			(stroke
				(width 0.1524)
				(type default)
			)
			(layer "B.SilkS")
		)
		(fp_line
			(start 0.7874 0.4064)
			(end 0.7874 -0.4064)
			(stroke
				(width 0.1524)
				(type default)
			)
			(layer "B.SilkS")
		)
		(fp_line
			(start -0.67945 -0.3048)
			(end -0.67945 0.3048)
			(stroke
				(width 0.1)
				(type default)
			)
			(layer "B.Fab")
		)
		(fp_line
			(start -0.67945 0.3048)
			(end -0.120396 0.3048)
			(stroke
				(width 0.1)
				(type default)
			)
			(layer "B.Fab")
		)
		(fp_line
			(start -0.12065 -0.3048)
			(end -0.67945 -0.3048)
			(stroke
				(width 0.1)
				(type default)
			)
			(layer "B.Fab")
		)
		(fp_line
			(start -0.12065 -0.2794)
			(end -0.12065 -0.3048)
			(stroke
				(width 0.1)
				(type default)
			)
			(layer "B.Fab")
		)
		(fp_line
			(start -0.120396 0.2794)
			(end 0.12065 0.2794)
			(stroke
				(width 0.1)
				(type default)
			)
			(layer "B.Fab")
		)
		(fp_line
			(start -0.120396 0.3048)
			(end -0.120396 0.2794)
			(stroke
				(width 0.1)
				(type default)
			)
			(layer "B.Fab")
		)
		(fp_line
			(start 0.12065 -0.305054)
			(end 0.12065 -0.2794)
			(stroke
				(width 0.1)
				(type default)
			)
			(layer "B.Fab")
		)
		(fp_line
			(start 0.12065 -0.2794)
			(end -0.12065 -0.2794)
			(stroke
				(width 0.1)
				(type default)
			)
			(layer "B.Fab")
		)
		(fp_line
			(start 0.12065 0.2794)
			(end 0.12065 0.3048)
			(stroke
				(width 0.1)
				(type default)
			)
			(layer "B.Fab")
		)
		(fp_line
			(start 0.12065 0.3048)
			(end 0.67945 0.3048)
			(stroke
				(width 0.1)
				(type default)
			)
			(layer "B.Fab")
		)
		(fp_line
			(start 0.67945 -0.305054)
			(end 0.12065 -0.305054)
			(stroke
				(width 0.1)
				(type default)
			)
			(layer "B.Fab")
		)
		(fp_line
			(start 0.67945 0.3048)
			(end 0.67945 -0.305054)
			(stroke
				(width 0.1)
				(type default)
			)
			(layer "B.Fab")
		)
		(pad "1" smd circle
			(at 0.40005 0 180)
			(size 0 0)
			(layers "B.Cu" "B.Mask" "B.Paste")
			(net "P1V2_CPU0_USB2_DVDD12")
		)
		(pad "2" smd circle
			(at -0.40005 0 180)
			(size 0 0)
			(layers "B.Cu" "B.Mask" "B.Paste")
			(net "GND")
		)
	)
	(footprint ""
		(layer "B.Cu")
		(at 371.297454 -266.00531)
		(property "Reference" "C2652"
			(at 0 0 0)
			(layer "B.SilkS")
			(hide yes)
			(effects
				(font
					(size 1.27 1.27)
				)
				(justify mirror)
			)
		)
		(property "Value" ""
			(at 0 0 0)
			(layer "B.Fab")
			(effects
				(font
					(size 1.27 1.27)
				)
				(justify mirror)
			)
		)
		(duplicate_pad_numbers_are_jumpers no)
		(fp_line
			(start -0.7874 -0.4064)
			(end -0.7874 0.4064)
			(stroke
				(width 0.1524)
				(type default)
			)
			(layer "B.SilkS")
		)
		(fp_line
			(start -0.7874 0.4064)
			(end 0.7874 0.4064)
			(stroke
				(width 0.1524)
				(type default)
			)
			(layer "B.SilkS")
		)
		(fp_line
			(start 0.7874 -0.4064)
			(end -0.7874 -0.4064)
			(stroke
				(width 0.1524)
				(type default)
			)
			(layer "B.SilkS")
		)
		(fp_line
			(start 0.7874 0.4064)
			(end 0.7874 -0.4064)
			(stroke
				(width 0.1524)
				(type default)
			)
			(layer "B.SilkS")
		)
		(fp_line
			(start -0.67945 -0.3048)
			(end -0.67945 0.3048)
			(stroke
				(width 0.1)
				(type default)
			)
			(layer "B.Fab")
		)
		(fp_line
			(start -0.67945 0.3048)
			(end -0.120396 0.3048)
			(stroke
				(width 0.1)
				(type default)
			)
			(layer "B.Fab")
		)
		(fp_line
			(start -0.12065 -0.3048)
			(end -0.67945 -0.3048)
			(stroke
				(width 0.1)
				(type default)
			)
			(layer "B.Fab")
		)
		(fp_line
			(start -0.12065 -0.2794)
			(end -0.12065 -0.3048)
			(stroke
				(width 0.1)
				(type default)
			)
			(layer "B.Fab")
		)
		(fp_line
			(start -0.120396 0.2794)
			(end 0.12065 0.2794)
			(stroke
				(width 0.1)
				(type default)
			)
			(layer "B.Fab")
		)
		(fp_line
			(start -0.120396 0.3048)
			(end -0.120396 0.2794)
			(stroke
				(width 0.1)
				(type default)
			)
			(layer "B.Fab")
		)
		(fp_line
			(start 0.12065 -0.305054)
			(end 0.12065 -0.2794)
			(stroke
				(width 0.1)
				(type default)
			)
			(layer "B.Fab")
		)
		(fp_line
			(start 0.12065 -0.2794)
			(end -0.12065 -0.2794)
			(stroke
				(width 0.1)
				(type default)
			)
			(layer "B.Fab")
		)
		(fp_line
			(start 0.12065 0.2794)
			(end 0.12065 0.3048)
			(stroke
				(width 0.1)
				(type default)
			)
			(layer "B.Fab")
		)
		(fp_line
			(start 0.12065 0.3048)
			(end 0.67945 0.3048)
			(stroke
				(width 0.1)
				(type default)
			)
			(layer "B.Fab")
		)
		(fp_line
			(start 0.67945 -0.305054)
			(end 0.12065 -0.305054)
			(stroke
				(width 0.1)
				(type default)
			)
			(layer "B.Fab")
		)
		(fp_line
			(start 0.67945 0.3048)
			(end 0.67945 -0.305054)
			(stroke
				(width 0.1)
				(type default)
			)
			(layer "B.Fab")
		)
		(pad "1" smd circle
			(at 0.40005 0 180)
			(size 0 0)
			(layers "B.Cu" "B.Mask" "B.Paste")
			(net "PVDD11_S3_P0")
		)
		(pad "2" smd circle
			(at -0.40005 0 180)
			(size 0 0)
			(layers "B.Cu" "B.Mask" "B.Paste")
			(net "GND")
		)
	)
	(footprint ""
		(layer "B.Cu")
		(at 107.675934 -256.012442 -90)
		(property "Reference" "C2408"
			(at 0 0 90)
			(layer "B.SilkS")
			(hide yes)
			(effects
				(font
					(size 1.27 1.27)
				)
				(justify mirror)
			)
		)
		(property "Value" ""
			(at 0 0 90)
			(layer "B.Fab")
			(effects
				(font
					(size 1.27 1.27)
				)
				(justify mirror)
			)
		)
		(duplicate_pad_numbers_are_jumpers no)
		(fp_line
			(start -0.7874 0.4064)
			(end 0.7874 0.4064)
			(stroke
				(width 0.1524)
				(type default)
			)
			(layer "B.SilkS")
		)
		(fp_line
			(start 0.7874 0.4064)
			(end 0.7874 -0.4064)
			(stroke
				(width 0.1524)
				(type default)
			)
			(layer "B.SilkS")
		)
		(fp_line
			(start -0.7874 -0.4064)
			(end -0.7874 0.4064)
			(stroke
				(width 0.1524)
				(type default)
			)
			(layer "B.SilkS")
		)
		(fp_line
			(start 0.7874 -0.4064)
			(end -0.7874 -0.4064)
			(stroke
				(width 0.1524)
				(type default)
			)
			(layer "B.SilkS")
		)
		(fp_line
			(start -0.67945 0.3048)
			(end -0.120396 0.3048)
			(stroke
				(width 0.1)
				(type default)
			)
			(layer "B.Fab")
		)
		(fp_line
			(start -0.120396 0.3048)
			(end -0.120396 0.2794)
			(stroke
				(width 0.1)
				(type default)
			)
			(layer "B.Fab")
		)
		(fp_line
			(start 0.12065 0.3048)
			(end 0.67945 0.3048)
			(stroke
				(width 0.1)
				(type default)
			)
			(layer "B.Fab")
		)
		(fp_line
			(start 0.67945 0.3048)
			(end 0.67945 -0.305054)
			(stroke
				(width 0.1)
				(type default)
			)
			(layer "B.Fab")
		)
		(fp_line
			(start -0.120396 0.2794)
			(end 0.12065 0.2794)
			(stroke
				(width 0.1)
				(type default)
			)
			(layer "B.Fab")
		)
		(fp_line
			(start 0.12065 0.2794)
			(end 0.12065 0.3048)
			(stroke
				(width 0.1)
				(type default)
			)
			(layer "B.Fab")
		)
		(fp_line
			(start -0.12065 -0.2794)
			(end -0.12065 -0.3048)
			(stroke
				(width 0.1)
				(type default)
			)
			(layer "B.Fab")
		)
		(fp_line
			(start 0.12065 -0.2794)
			(end -0.12065 -0.2794)
			(stroke
				(width 0.1)
				(type default)
			)
			(layer "B.Fab")
		)
		(fp_line
			(start -0.67945 -0.3048)
			(end -0.67945 0.3048)
			(stroke
				(width 0.1)
				(type default)
			)
			(layer "B.Fab")
		)
		(fp_line
			(start -0.12065 -0.3048)
			(end -0.67945 -0.3048)
			(stroke
				(width 0.1)
				(type default)
			)
			(layer "B.Fab")
		)
		(fp_line
			(start 0.12065 -0.305054)
			(end 0.12065 -0.2794)
			(stroke
				(width 0.1)
				(type default)
			)
			(layer "B.Fab")
		)
		(fp_line
			(start 0.67945 -0.305054)
			(end 0.12065 -0.305054)
			(stroke
				(width 0.1)
				(type default)
			)
			(layer "B.Fab")
		)
		(pad "1" smd circle
			(at 0.40005 0 90)
			(size 0 0)
			(layers "B.Cu" "B.Mask" "B.Paste")
			(net "PVDDCR_SOC_P1")
		)
		(pad "2" smd circle
			(at -0.40005 0 90)
			(size 0 0)
			(layers "B.Cu" "B.Mask" "B.Paste")
			(net "GND")
		)
	)
	(footprint ""
		(layer "B.Cu")
		(at 384.113278 -139.186158 180)
		(property "Reference" "PC7"
			(at 0 0 0)
			(layer "B.SilkS")
			(hide yes)
			(effects
				(font
					(size 1.27 1.27)
				)
				(justify mirror)
			)
		)
		(property "Value" ""
			(at 0 0 0)
			(layer "B.Fab")
			(effects
				(font
					(size 1.27 1.27)
				)
				(justify mirror)
			)
		)
		(duplicate_pad_numbers_are_jumpers no)
		(fp_line
			(start 0.7874 0.4064)
			(end 0.7874 -0.4064)
			(stroke
				(width 0.1524)
				(type default)
			)
			(layer "B.SilkS")
		)
		(fp_line
			(start 0.7874 -0.4064)
			(end -0.7874 -0.4064)
			(stroke
				(width 0.1524)
				(type default)
			)
			(layer "B.SilkS")
		)
		(fp_line
			(start -0.7874 0.4064)
			(end 0.7874 0.4064)
			(stroke
				(width 0.1524)
				(type default)
			)
			(layer "B.SilkS")
		)
		(fp_line
			(start -0.7874 -0.4064)
			(end -0.7874 0.4064)
			(stroke
				(width 0.1524)
				(type default)
			)
			(layer "B.SilkS")
		)
		(fp_line
			(start 0.67945 0.3048)
			(end 0.67945 -0.305054)
			(stroke
				(width 0.1)
				(type default)
			)
			(layer "B.Fab")
		)
		(fp_line
			(start 0.67945 -0.305054)
			(end 0.12065 -0.305054)
			(stroke
				(width 0.1)
				(type default)
			)
			(layer "B.Fab")
		)
		(fp_line
			(start 0.12065 0.3048)
			(end 0.67945 0.3048)
			(stroke
				(width 0.1)
				(type default)
			)
			(layer "B.Fab")
		)
		(fp_line
			(start 0.12065 0.2794)
			(end 0.12065 0.3048)
			(stroke
				(width 0.1)
				(type default)
			)
			(layer "B.Fab")
		)
		(fp_line
			(start 0.12065 -0.2794)
			(end -0.12065 -0.2794)
			(stroke
				(width 0.1)
				(type default)
			)
			(layer "B.Fab")
		)
		(fp_line
			(start 0.12065 -0.305054)
			(end 0.12065 -0.2794)
			(stroke
				(width 0.1)
				(type default)
			)
			(layer "B.Fab")
		)
		(fp_line
			(start -0.120396 0.3048)
			(end -0.120396 0.2794)
			(stroke
				(width 0.1)
				(type default)
			)
			(layer "B.Fab")
		)
		(fp_line
			(start -0.120396 0.2794)
			(end 0.12065 0.2794)
			(stroke
				(width 0.1)
				(type default)
			)
			(layer "B.Fab")
		)
		(fp_line
			(start -0.12065 -0.2794)
			(end -0.12065 -0.3048)
			(stroke
				(width 0.1)
				(type default)
			)
			(layer "B.Fab")
		)
		(fp_line
			(start -0.12065 -0.3048)
			(end -0.67945 -0.3048)
			(stroke
				(width 0.1)
				(type default)
			)
			(layer "B.Fab")
		)
		(fp_line
			(start -0.67945 0.3048)
			(end -0.120396 0.3048)
			(stroke
				(width 0.1)
				(type default)
			)
			(layer "B.Fab")
		)
		(fp_line
			(start -0.67945 -0.3048)
			(end -0.67945 0.3048)
			(stroke
				(width 0.1)
				(type default)
			)
			(layer "B.Fab")
		)
		(pad "1" smd circle
			(at 0.40005 0)
			(size 0 0)
			(layers "B.Cu" "B.Mask" "B.Paste")
			(net "PVDDCR_CPU0_P0_VINSEN")
		)
		(pad "2" smd circle
			(at -0.40005 0)
			(size 0 0)
			(layers "B.Cu" "B.Mask" "B.Paste")
			(net "GND")
		)
	)
	(footprint ""
		(layer "B.Cu")
		(at 70.252336 -384.575558)
		(property "Reference" "L3"
			(at 0 0 0)
			(layer "B.SilkS")
			(hide yes)
			(effects
				(font
					(size 1.27 1.27)
				)
				(justify mirror)
			)
		)
		(property "Value" ""
			(at 0 0 0)
			(layer "B.Fab")
			(effects
				(font
					(size 1.27 1.27)
				)
				(justify mirror)
			)
		)
		(duplicate_pad_numbers_are_jumpers no)
		(fp_line
			(start -1.63576 -0.8128)
			(end -1.63576 0.8128)
			(stroke
				(width 0.1524)
				(type default)
			)
			(layer "B.SilkS")
		)
		(fp_line
			(start -1.63576 0.8128)
			(end 1.63576 0.8128)
			(stroke
				(width 0.1524)
				(type default)
			)
			(layer "B.SilkS")
		)
		(fp_line
			(start 1.63576 -0.8128)
			(end -1.63576 -0.8128)
			(stroke
				(width 0.1524)
				(type default)
			)
			(layer "B.SilkS")
		)
		(fp_line
			(start 1.63576 -0.8128)
			(end 1.63576 0.8128)
			(stroke
				(width 0.1524)
				(type default)
			)
			(layer "B.SilkS")
		)
		(fp_line
			(start -1.560576 -0.738632)
			(end 1.56083 -0.738632)
			(stroke
				(width 0.1)
				(type default)
			)
			(layer "B.Fab")
		)
		(fp_line
			(start -1.560576 0.7366)
			(end -1.560576 -0.738632)
			(stroke
				(width 0.1)
				(type default)
			)
			(layer "B.Fab")
		)
		(fp_line
			(start -1.524 0.7366)
			(end -1.560576 0.7366)
			(stroke
				(width 0.1)
				(type default)
			)
			(layer "B.Fab")
		)
		(fp_line
			(start 1.524 0.7366)
			(end -1.524 0.7366)
			(stroke
				(width 0.1)
				(type default)
			)
			(layer "B.Fab")
		)
		(fp_line
			(start 1.56083 -0.738632)
			(end 1.56083 0.7366)
			(stroke
				(width 0.1)
				(type default)
			)
			(layer "B.Fab")
		)
		(fp_line
			(start 1.56083 0.7366)
			(end 1.524 0.7366)
			(stroke
				(width 0.1)
				(type default)
			)
			(layer "B.Fab")
		)
		(pad "1" smd rect
			(at 0.94996 0)
			(size 1.1176 1.3716)
			(layers "B.Cu" "B.Mask" "B.Paste")
			(net "P1V8_CPU1_RT_1D")
		)
		(pad "2" smd rect
			(at -0.94996 0)
			(size 1.1176 1.3716)
			(layers "B.Cu" "B.Mask" "B.Paste")
			(net "P1V8_CPU1_RT0_1A")
		)
	)
	(footprint ""
		(layer "B.Cu")
		(at 348.913958 -249.36831 180)
		(property "Reference" "C2167"
			(at 0 0 0)
			(layer "B.SilkS")
			(hide yes)
			(effects
				(font
					(size 1.27 1.27)
				)
				(justify mirror)
			)
		)
		(property "Value" ""
			(at 0 0 0)
			(layer "B.Fab")
			(effects
				(font
					(size 1.27 1.27)
				)
				(justify mirror)
			)
		)
		(duplicate_pad_numbers_are_jumpers no)
		(fp_line
			(start 0.7874 0.4064)
			(end 0.7874 -0.4064)
			(stroke
				(width 0.1524)
				(type default)
			)
			(layer "B.SilkS")
		)
		(fp_line
			(start 0.7874 -0.4064)
			(end -0.7874 -0.4064)
			(stroke
				(width 0.1524)
				(type default)
			)
			(layer "B.SilkS")
		)
		(fp_line
			(start -0.7874 0.4064)
			(end 0.7874 0.4064)
			(stroke
				(width 0.1524)
				(type default)
			)
			(layer "B.SilkS")
		)
		(fp_line
			(start -0.7874 -0.4064)
			(end -0.7874 0.4064)
			(stroke
				(width 0.1524)
				(type default)
			)
			(layer "B.SilkS")
		)
		(fp_line
			(start 0.67945 0.3048)
			(end 0.67945 -0.305054)
			(stroke
				(width 0.1)
				(type default)
			)
			(layer "B.Fab")
		)
		(fp_line
			(start 0.67945 -0.305054)
			(end 0.12065 -0.305054)
			(stroke
				(width 0.1)
				(type default)
			)
			(layer "B.Fab")
		)
		(fp_line
			(start 0.12065 0.3048)
			(end 0.67945 0.3048)
			(stroke
				(width 0.1)
				(type default)
			)
			(layer "B.Fab")
		)
		(fp_line
			(start 0.12065 0.2794)
			(end 0.12065 0.3048)
			(stroke
				(width 0.1)
				(type default)
			)
			(layer "B.Fab")
		)
		(fp_line
			(start 0.12065 -0.2794)
			(end -0.12065 -0.2794)
			(stroke
				(width 0.1)
				(type default)
			)
			(layer "B.Fab")
		)
		(fp_line
			(start 0.12065 -0.305054)
			(end 0.12065 -0.2794)
			(stroke
				(width 0.1)
				(type default)
			)
			(layer "B.Fab")
		)
		(fp_line
			(start -0.120396 0.3048)
			(end -0.120396 0.2794)
			(stroke
				(width 0.1)
				(type default)
			)
			(layer "B.Fab")
		)
		(fp_line
			(start -0.120396 0.2794)
			(end 0.12065 0.2794)
			(stroke
				(width 0.1)
				(type default)
			)
			(layer "B.Fab")
		)
		(fp_line
			(start -0.12065 -0.2794)
			(end -0.12065 -0.3048)
			(stroke
				(width 0.1)
				(type default)
			)
			(layer "B.Fab")
		)
		(fp_line
			(start -0.12065 -0.3048)
			(end -0.67945 -0.3048)
			(stroke
				(width 0.1)
				(type default)
			)
			(layer "B.Fab")
		)
		(fp_line
			(start -0.67945 0.3048)
			(end -0.120396 0.3048)
			(stroke
				(width 0.1)
				(type default)
			)
			(layer "B.Fab")
		)
		(fp_line
			(start -0.67945 -0.3048)
			(end -0.67945 0.3048)
			(stroke
				(width 0.1)
				(type default)
			)
			(layer "B.Fab")
		)
		(pad "1" smd circle
			(at 0.40005 0)
			(size 0 0)
			(layers "B.Cu" "B.Mask" "B.Paste")
			(net "PVDDCR_CPU0_P0")
		)
		(pad "2" smd circle
			(at -0.40005 0)
			(size 0 0)
			(layers "B.Cu" "B.Mask" "B.Paste")
			(net "GND")
		)
	)
)
